(kicad_pcb
	(version 20260206)
	(generator "pcbnew")
	(generator_version "10.0")
	(general
		(thickness 1.6)
		(legacy_teardrops no)
	)
	(paper "A4")
	(title_block
		(title "03242023_DA0F0TMBIJ0_F0T_Motherboard_J_brd_V01_OCP.brd")
		(comment 1 "Grand Teton / footprints 1459-1465 of 6105")
	)
	(layers
		(0 "F.Cu" signal "TOP")
		(4 "In1.Cu" signal "GND")
		(6 "In2.Cu" signal "IN1")
		(8 "In3.Cu" signal "GND1")
		(10 "In4.Cu" signal "IN2")
		(12 "In5.Cu" signal "GND2")
		(14 "In6.Cu" signal "IN3")
		(16 "In7.Cu" signal "GND3")
		(18 "In8.Cu" signal "VCC")
		(20 "In9.Cu" signal "VCC1")
		(22 "In10.Cu" signal "GND4")
		(24 "In11.Cu" signal "IN4")
		(26 "In12.Cu" signal "GND5")
		(28 "In13.Cu" signal "IN5")
		(30 "In14.Cu" signal "GND6")
		(32 "In15.Cu" signal "IN6")
		(34 "In16.Cu" signal "GND7")
		(2 "B.Cu" signal "BOTTOM")
		(9 "F.Adhes" user "F.Adhesive")
		(11 "B.Adhes" user "B.Adhesive")
		(13 "F.Paste" user "Package Geometry/Pastemask Top")
		(15 "B.Paste" user "Package Geometry/Pastemask Bottom")
		(5 "F.SilkS" user "Ref Des/Silkscreen Top")
		(7 "B.SilkS" user "Ref Des/Silkscreen Bottom")
		(1 "F.Mask" user "Board Geometry/Soldermask Top")
		(3 "B.Mask" user "Board Geometry/Soldermask Bottom")
		(17 "Dwgs.User" user "User.Drawings")
		(19 "Cmts.User" user "User.Comments")
		(21 "Eco1.User" user "User.Eco1")
		(23 "Eco2.User" user "User.Eco2")
		(25 "Edge.Cuts" user "Board Geometry/Outline")
		(27 "Margin" user)
		(31 "F.CrtYd" user "Package Geometry/Place Bound Top")
		(29 "B.CrtYd" user "Package Geometry/Place Bound Bottom")
		(35 "F.Fab" user "Ref Des/Assembly Top")
		(33 "B.Fab" user "Ref Des/Assembly Bottom")
	)
	(footprint ""
		(layer "F.Cu")
		(at 155.27909 -46.751748 180)
		(property "Reference" "R4486"
			(at 0 0 180)
			(layer "F.SilkS")
			(hide yes)
			(effects
				(font
					(size 1.27 1.27)
				)
			)
		)
		(property "Value" ""
			(at 0 0 180)
			(layer "F.Fab")
			(effects
				(font
					(size 1.27 1.27)
				)
			)
		)
		(duplicate_pad_numbers_are_jumpers no)
		(fp_line
			(start 0.7874 0.4064)
			(end -0.08763 0.4064)
			(stroke
				(width 0.1524)
				(type default)
			)
			(layer "F.SilkS")
		)
		(fp_line
			(start 0.7874 -0.4064)
			(end 0.7874 0.4064)
			(stroke
				(width 0.1524)
				(type default)
			)
			(layer "F.SilkS")
		)
		(fp_line
			(start 0.05715 -0.4064)
			(end 0.7874 -0.4064)
			(stroke
				(width 0.1524)
				(type default)
			)
			(layer "F.SilkS")
		)
		(fp_line
			(start 0.67945 0.3048)
			(end 0.120396 0.3048)
			(stroke
				(width 0.1)
				(type default)
			)
			(layer "F.Fab")
		)
		(fp_line
			(start 0.67945 -0.3048)
			(end 0.67945 0.3048)
			(stroke
				(width 0.1)
				(type default)
			)
			(layer "F.Fab")
		)
		(fp_line
			(start 0.12065 -0.2794)
			(end 0.12065 -0.3048)
			(stroke
				(width 0.1)
				(type default)
			)
			(layer "F.Fab")
		)
		(fp_line
			(start 0.12065 -0.3048)
			(end 0.67945 -0.3048)
			(stroke
				(width 0.1)
				(type default)
			)
			(layer "F.Fab")
		)
		(fp_line
			(start 0.120396 0.3048)
			(end 0.120396 0.2794)
			(stroke
				(width 0.1)
				(type default)
			)
			(layer "F.Fab")
		)
		(fp_line
			(start 0.120396 0.2794)
			(end -0.12065 0.2794)
			(stroke
				(width 0.1)
				(type default)
			)
			(layer "F.Fab")
		)
		(fp_line
			(start -0.12065 0.3048)
			(end -0.67945 0.3048)
			(stroke
				(width 0.1)
				(type default)
			)
			(layer "F.Fab")
		)
		(fp_line
			(start -0.12065 0.2794)
			(end -0.12065 0.3048)
			(stroke
				(width 0.1)
				(type default)
			)
			(layer "F.Fab")
		)
		(fp_line
			(start -0.12065 -0.2794)
			(end 0.12065 -0.2794)
			(stroke
				(width 0.1)
				(type default)
			)
			(layer "F.Fab")
		)
		(fp_line
			(start -0.12065 -0.305054)
			(end -0.12065 -0.2794)
			(stroke
				(width 0.1)
				(type default)
			)
			(layer "F.Fab")
		)
		(fp_line
			(start -0.67945 0.3048)
			(end -0.67945 -0.305054)
			(stroke
				(width 0.1)
				(type default)
			)
			(layer "F.Fab")
		)
		(fp_line
			(start -0.67945 -0.305054)
			(end -0.12065 -0.305054)
			(stroke
				(width 0.1)
				(type default)
			)
			(layer "F.Fab")
		)
		(pad "1" smd circle
			(at -0.40005 0 180)
			(size 0 0)
			(layers "F.Cu" "F.Mask" "F.Paste")
			(net "USB2_HOST_PCH_0_DP")
		)
		(pad "2" smd circle
			(at 0.40005 0 180)
			(size 0 0)
			(layers "F.Cu" "F.Mask" "F.Paste")
			(net "GND")
		)
	)
	(footprint ""
		(layer "F.Cu")
		(at 465.821014 -118.699534 180)
		(property "Reference" "R1131"
			(at 0 0 180)
			(layer "F.SilkS")
			(hide yes)
			(effects
				(font
					(size 1.27 1.27)
				)
			)
		)
		(property "Value" ""
			(at 0 0 180)
			(layer "F.Fab")
			(effects
				(font
					(size 1.27 1.27)
				)
			)
		)
		(duplicate_pad_numbers_are_jumpers no)
		(fp_line
			(start 0.7874 0.4064)
			(end -0.7874 0.4064)
			(stroke
				(width 0.1524)
				(type default)
			)
			(layer "F.SilkS")
		)
		(fp_line
			(start 0.7874 -0.4064)
			(end 0.7874 0.4064)
			(stroke
				(width 0.1524)
				(type default)
			)
			(layer "F.SilkS")
		)
		(fp_line
			(start -0.7874 0.4064)
			(end -0.7874 -0.4064)
			(stroke
				(width 0.1524)
				(type default)
			)
			(layer "F.SilkS")
		)
		(fp_line
			(start -0.7874 -0.4064)
			(end 0.7874 -0.4064)
			(stroke
				(width 0.1524)
				(type default)
			)
			(layer "F.SilkS")
		)
		(fp_line
			(start 0.67945 0.3048)
			(end 0.120396 0.3048)
			(stroke
				(width 0.1)
				(type default)
			)
			(layer "F.Fab")
		)
		(fp_line
			(start 0.67945 -0.3048)
			(end 0.67945 0.3048)
			(stroke
				(width 0.1)
				(type default)
			)
			(layer "F.Fab")
		)
		(fp_line
			(start 0.12065 -0.2794)
			(end 0.12065 -0.3048)
			(stroke
				(width 0.1)
				(type default)
			)
			(layer "F.Fab")
		)
		(fp_line
			(start 0.12065 -0.3048)
			(end 0.67945 -0.3048)
			(stroke
				(width 0.1)
				(type default)
			)
			(layer "F.Fab")
		)
		(fp_line
			(start 0.120396 0.3048)
			(end 0.120396 0.2794)
			(stroke
				(width 0.1)
				(type default)
			)
			(layer "F.Fab")
		)
		(fp_line
			(start 0.120396 0.2794)
			(end -0.12065 0.2794)
			(stroke
				(width 0.1)
				(type default)
			)
			(layer "F.Fab")
		)
		(fp_line
			(start -0.12065 0.3048)
			(end -0.67945 0.3048)
			(stroke
				(width 0.1)
				(type default)
			)
			(layer "F.Fab")
		)
		(fp_line
			(start -0.12065 0.2794)
			(end -0.12065 0.3048)
			(stroke
				(width 0.1)
				(type default)
			)
			(layer "F.Fab")
		)
		(fp_line
			(start -0.12065 -0.2794)
			(end 0.12065 -0.2794)
			(stroke
				(width 0.1)
				(type default)
			)
			(layer "F.Fab")
		)
		(fp_line
			(start -0.12065 -0.305054)
			(end -0.12065 -0.2794)
			(stroke
				(width 0.1)
				(type default)
			)
			(layer "F.Fab")
		)
		(fp_line
			(start -0.67945 0.3048)
			(end -0.67945 -0.305054)
			(stroke
				(width 0.1)
				(type default)
			)
			(layer "F.Fab")
		)
		(fp_line
			(start -0.67945 -0.305054)
			(end -0.12065 -0.305054)
			(stroke
				(width 0.1)
				(type default)
			)
			(layer "F.Fab")
		)
		(pad "1" smd circle
			(at -0.40005 0 180)
			(size 0 0)
			(layers "F.Cu" "F.Mask" "F.Paste")
			(net "SMB_PEHPCPU0_LVC3_SDA")
		)
		(pad "2" smd circle
			(at 0.40005 0 180)
			(size 0 0)
			(layers "F.Cu" "F.Mask" "F.Paste")
			(net "SMB_PEHPCPU0_LVC3_R_SDA")
		)
	)
	(footprint ""
		(layer "F.Cu")
		(at 220.087444 -97.13341)
		(property "Reference" "R2222"
			(at 0 0 0)
			(layer "F.SilkS")
			(hide yes)
			(effects
				(font
					(size 1.27 1.27)
				)
			)
		)
		(property "Value" ""
			(at 0 0 0)
			(layer "F.Fab")
			(effects
				(font
					(size 1.27 1.27)
				)
			)
		)
		(duplicate_pad_numbers_are_jumpers no)
		(fp_line
			(start -0.7874 -0.4064)
			(end 0.7874 -0.4064)
			(stroke
				(width 0.1524)
				(type default)
			)
			(layer "F.SilkS")
		)
		(fp_line
			(start -0.7874 0.4064)
			(end -0.7874 -0.4064)
			(stroke
				(width 0.1524)
				(type default)
			)
			(layer "F.SilkS")
		)
		(fp_line
			(start 0.7874 -0.4064)
			(end 0.7874 0.4064)
			(stroke
				(width 0.1524)
				(type default)
			)
			(layer "F.SilkS")
		)
		(fp_line
			(start 0.7874 0.4064)
			(end -0.7874 0.4064)
			(stroke
				(width 0.1524)
				(type default)
			)
			(layer "F.SilkS")
		)
		(fp_line
			(start -0.67945 -0.305054)
			(end -0.12065 -0.305054)
			(stroke
				(width 0.1)
				(type default)
			)
			(layer "F.Fab")
		)
		(fp_line
			(start -0.67945 0.3048)
			(end -0.67945 -0.305054)
			(stroke
				(width 0.1)
				(type default)
			)
			(layer "F.Fab")
		)
		(fp_line
			(start -0.12065 -0.305054)
			(end -0.12065 -0.2794)
			(stroke
				(width 0.1)
				(type default)
			)
			(layer "F.Fab")
		)
		(fp_line
			(start -0.12065 -0.2794)
			(end 0.12065 -0.2794)
			(stroke
				(width 0.1)
				(type default)
			)
			(layer "F.Fab")
		)
		(fp_line
			(start -0.12065 0.2794)
			(end -0.12065 0.3048)
			(stroke
				(width 0.1)
				(type default)
			)
			(layer "F.Fab")
		)
		(fp_line
			(start -0.12065 0.3048)
			(end -0.67945 0.3048)
			(stroke
				(width 0.1)
				(type default)
			)
			(layer "F.Fab")
		)
		(fp_line
			(start 0.120396 0.2794)
			(end -0.12065 0.2794)
			(stroke
				(width 0.1)
				(type default)
			)
			(layer "F.Fab")
		)
		(fp_line
			(start 0.120396 0.3048)
			(end 0.120396 0.2794)
			(stroke
				(width 0.1)
				(type default)
			)
			(layer "F.Fab")
		)
		(fp_line
			(start 0.12065 -0.3048)
			(end 0.67945 -0.3048)
			(stroke
				(width 0.1)
				(type default)
			)
			(layer "F.Fab")
		)
		(fp_line
			(start 0.12065 -0.2794)
			(end 0.12065 -0.3048)
			(stroke
				(width 0.1)
				(type default)
			)
			(layer "F.Fab")
		)
		(fp_line
			(start 0.67945 -0.3048)
			(end 0.67945 0.3048)
			(stroke
				(width 0.1)
				(type default)
			)
			(layer "F.Fab")
		)
		(fp_line
			(start 0.67945 0.3048)
			(end 0.120396 0.3048)
			(stroke
				(width 0.1)
				(type default)
			)
			(layer "F.Fab")
		)
		(pad "1" smd circle
			(at -0.40005 0)
			(size 0 0)
			(layers "F.Cu" "F.Mask" "F.Paste")
			(net "A_P12V_STBY_FP_TRIGGER")
		)
		(pad "2" smd circle
			(at 0.40005 0)
			(size 0 0)
			(layers "F.Cu" "F.Mask" "F.Paste")
			(net "GND")
		)
	)
	(footprint ""
		(layer "F.Cu")
		(at 54.88686 -353.643946 -90)
		(property "Reference" "PC400_P1_2"
			(at 0 0 270)
			(layer "F.SilkS")
			(hide yes)
			(effects
				(font
					(size 1.27 1.27)
				)
			)
		)
		(property "Value" ""
			(at 0 0 270)
			(layer "F.Fab")
			(effects
				(font
					(size 1.27 1.27)
				)
			)
		)
		(duplicate_pad_numbers_are_jumpers no)
		(fp_line
			(start -0.7874 0.4064)
			(end -0.7874 -0.4064)
			(stroke
				(width 0.1524)
				(type default)
			)
			(layer "F.SilkS")
		)
		(fp_line
			(start 0.7874 0.4064)
			(end -0.7874 0.4064)
			(stroke
				(width 0.1524)
				(type default)
			)
			(layer "F.SilkS")
		)
		(fp_line
			(start -0.7874 -0.4064)
			(end 0.7874 -0.4064)
			(stroke
				(width 0.1524)
				(type default)
			)
			(layer "F.SilkS")
		)
		(fp_line
			(start 0.7874 -0.4064)
			(end 0.7874 0.4064)
			(stroke
				(width 0.1524)
				(type default)
			)
			(layer "F.SilkS")
		)
		(fp_line
			(start -0.67945 0.3048)
			(end -0.67945 -0.305054)
			(stroke
				(width 0.1)
				(type default)
			)
			(layer "F.Fab")
		)
		(fp_line
			(start -0.12065 0.3048)
			(end -0.67945 0.3048)
			(stroke
				(width 0.1)
				(type default)
			)
			(layer "F.Fab")
		)
		(fp_line
			(start 0.120396 0.3048)
			(end 0.120396 0.2794)
			(stroke
				(width 0.1)
				(type default)
			)
			(layer "F.Fab")
		)
		(fp_line
			(start 0.67945 0.3048)
			(end 0.120396 0.3048)
			(stroke
				(width 0.1)
				(type default)
			)
			(layer "F.Fab")
		)
		(fp_line
			(start -0.12065 0.2794)
			(end -0.12065 0.3048)
			(stroke
				(width 0.1)
				(type default)
			)
			(layer "F.Fab")
		)
		(fp_line
			(start 0.120396 0.2794)
			(end -0.12065 0.2794)
			(stroke
				(width 0.1)
				(type default)
			)
			(layer "F.Fab")
		)
		(fp_line
			(start -0.12065 -0.2794)
			(end 0.12065 -0.2794)
			(stroke
				(width 0.1)
				(type default)
			)
			(layer "F.Fab")
		)
		(fp_line
			(start 0.12065 -0.2794)
			(end 0.12065 -0.3048)
			(stroke
				(width 0.1)
				(type default)
			)
			(layer "F.Fab")
		)
		(fp_line
			(start 0.12065 -0.3048)
			(end 0.67945 -0.3048)
			(stroke
				(width 0.1)
				(type default)
			)
			(layer "F.Fab")
		)
		(fp_line
			(start 0.67945 -0.3048)
			(end 0.67945 0.3048)
			(stroke
				(width 0.1)
				(type default)
			)
			(layer "F.Fab")
		)
		(fp_line
			(start -0.67945 -0.305054)
			(end -0.12065 -0.305054)
			(stroke
				(width 0.1)
				(type default)
			)
			(layer "F.Fab")
		)
		(fp_line
			(start -0.12065 -0.305054)
			(end -0.12065 -0.2794)
			(stroke
				(width 0.1)
				(type default)
			)
			(layer "F.Fab")
		)
		(pad "1" smd circle
			(at -0.40005 0 270)
			(size 0 0)
			(layers "F.Cu" "F.Mask" "F.Paste")
			(net "SW_P12V_PVCCFA_EHV_FIVRA_CPU1_L")
		)
		(pad "2" smd circle
			(at 0.40005 0 270)
			(size 0 0)
			(layers "F.Cu" "F.Mask" "F.Paste")
			(net "GND")
		)
	)
	(footprint ""
		(layer "F.Cu")
		(at 169.422572 -419.495478)
		(property "Reference" "R3438"
			(at 0 0 0)
			(layer "F.SilkS")
			(hide yes)
			(effects
				(font
					(size 1.27 1.27)
				)
			)
		)
		(property "Value" ""
			(at 0 0 0)
			(layer "F.Fab")
			(effects
				(font
					(size 1.27 1.27)
				)
			)
		)
		(duplicate_pad_numbers_are_jumpers no)
		(fp_line
			(start -0.7874 -0.4064)
			(end 0.7874 -0.4064)
			(stroke
				(width 0.1524)
				(type default)
			)
			(layer "F.SilkS")
		)
		(fp_line
			(start -0.7874 0.4064)
			(end -0.7874 -0.4064)
			(stroke
				(width 0.1524)
				(type default)
			)
			(layer "F.SilkS")
		)
		(fp_line
			(start 0.7874 -0.4064)
			(end 0.7874 0.4064)
			(stroke
				(width 0.1524)
				(type default)
			)
			(layer "F.SilkS")
		)
		(fp_line
			(start 0.7874 0.4064)
			(end -0.7874 0.4064)
			(stroke
				(width 0.1524)
				(type default)
			)
			(layer "F.SilkS")
		)
		(fp_line
			(start -0.67945 -0.305054)
			(end -0.12065 -0.305054)
			(stroke
				(width 0.1)
				(type default)
			)
			(layer "F.Fab")
		)
		(fp_line
			(start -0.67945 0.3048)
			(end -0.67945 -0.305054)
			(stroke
				(width 0.1)
				(type default)
			)
			(layer "F.Fab")
		)
		(fp_line
			(start -0.12065 -0.305054)
			(end -0.12065 -0.2794)
			(stroke
				(width 0.1)
				(type default)
			)
			(layer "F.Fab")
		)
		(fp_line
			(start -0.12065 -0.2794)
			(end 0.12065 -0.2794)
			(stroke
				(width 0.1)
				(type default)
			)
			(layer "F.Fab")
		)
		(fp_line
			(start -0.12065 0.2794)
			(end -0.12065 0.3048)
			(stroke
				(width 0.1)
				(type default)
			)
			(layer "F.Fab")
		)
		(fp_line
			(start -0.12065 0.3048)
			(end -0.67945 0.3048)
			(stroke
				(width 0.1)
				(type default)
			)
			(layer "F.Fab")
		)
		(fp_line
			(start 0.120396 0.2794)
			(end -0.12065 0.2794)
			(stroke
				(width 0.1)
				(type default)
			)
			(layer "F.Fab")
		)
		(fp_line
			(start 0.120396 0.3048)
			(end 0.120396 0.2794)
			(stroke
				(width 0.1)
				(type default)
			)
			(layer "F.Fab")
		)
		(fp_line
			(start 0.12065 -0.3048)
			(end 0.67945 -0.3048)
			(stroke
				(width 0.1)
				(type default)
			)
			(layer "F.Fab")
		)
		(fp_line
			(start 0.12065 -0.2794)
			(end 0.12065 -0.3048)
			(stroke
				(width 0.1)
				(type default)
			)
			(layer "F.Fab")
		)
		(fp_line
			(start 0.67945 -0.3048)
			(end 0.67945 0.3048)
			(stroke
				(width 0.1)
				(type default)
			)
			(layer "F.Fab")
		)
		(fp_line
			(start 0.67945 0.3048)
			(end 0.120396 0.3048)
			(stroke
				(width 0.1)
				(type default)
			)
			(layer "F.Fab")
		)
		(pad "1" smd circle
			(at -0.40005 0)
			(size 0 0)
			(layers "F.Cu" "F.Mask" "F.Paste")
			(net "P3V3_AUX")
		)
		(pad "2" smd circle
			(at 0.40005 0)
			(size 0 0)
			(layers "F.Cu" "F.Mask" "F.Paste")
			(net "GPU_BASE_HMC_READY_ISO")
		)
	)
	(footprint ""
		(layer "F.Cu")
		(at 237.205266 -297.147996)
		(property "Reference" "ME10"
			(at -9.7155 10.690352 0)
			(unlocked yes)
			(layer "F.SilkS")
			(effects
				(font
					(size 0.7874 0.5842)
					(thickness 0.1524)
				)
				(justify left)
			)
		)
		(property "Value" ""
			(at 0 0 0)
			(layer "F.Fab")
			(effects
				(font
					(size 1.27 1.27)
				)
			)
		)
		(duplicate_pad_numbers_are_jumpers no)
	)
	(footprint ""
		(layer "F.Cu")
		(at 149.81428 -32.929068)
		(property "Reference" "C1878"
			(at 0 0 0)
			(layer "F.SilkS")
			(hide yes)
			(effects
				(font
					(size 1.27 1.27)
				)
			)
		)
		(property "Value" ""
			(at 0 0 0)
			(layer "F.Fab")
			(effects
				(font
					(size 1.27 1.27)
				)
			)
		)
		(duplicate_pad_numbers_are_jumpers no)
		(fp_line
			(start -0.7874 -0.4064)
			(end 0.7874 -0.4064)
			(stroke
				(width 0.1524)
				(type default)
			)
			(layer "F.SilkS")
		)
		(fp_line
			(start -0.7874 0.4064)
			(end -0.7874 -0.4064)
			(stroke
				(width 0.1524)
				(type default)
			)
			(layer "F.SilkS")
		)
		(fp_line
			(start 0.7874 -0.4064)
			(end 0.7874 0.4064)
			(stroke
				(width 0.1524)
				(type default)
			)
			(layer "F.SilkS")
		)
		(fp_line
			(start 0.7874 0.4064)
			(end -0.7874 0.4064)
			(stroke
				(width 0.1524)
				(type default)
			)
			(layer "F.SilkS")
		)
		(fp_line
			(start -0.67945 -0.305054)
			(end -0.12065 -0.305054)
			(stroke
				(width 0.1)
				(type default)
			)
			(layer "F.Fab")
		)
		(fp_line
			(start -0.67945 0.3048)
			(end -0.67945 -0.305054)
			(stroke
				(width 0.1)
				(type default)
			)
			(layer "F.Fab")
		)
		(fp_line
			(start -0.12065 -0.305054)
			(end -0.12065 -0.2794)
			(stroke
				(width 0.1)
				(type default)
			)
			(layer "F.Fab")
		)
		(fp_line
			(start -0.12065 -0.2794)
			(end 0.12065 -0.2794)
			(stroke
				(width 0.1)
				(type default)
			)
			(layer "F.Fab")
		)
		(fp_line
			(start -0.12065 0.2794)
			(end -0.12065 0.3048)
			(stroke
				(width 0.1)
				(type default)
			)
			(layer "F.Fab")
		)
		(fp_line
			(start -0.12065 0.3048)
			(end -0.67945 0.3048)
			(stroke
				(width 0.1)
				(type default)
			)
			(layer "F.Fab")
		)
		(fp_line
			(start 0.120396 0.2794)
			(end -0.12065 0.2794)
			(stroke
				(width 0.1)
				(type default)
			)
			(layer "F.Fab")
		)
		(fp_line
			(start 0.120396 0.3048)
			(end 0.120396 0.2794)
			(stroke
				(width 0.1)
				(type default)
			)
			(layer "F.Fab")
		)
		(fp_line
			(start 0.12065 -0.3048)
			(end 0.67945 -0.3048)
			(stroke
				(width 0.1)
				(type default)
			)
			(layer "F.Fab")
		)
		(fp_line
			(start 0.12065 -0.2794)
			(end 0.12065 -0.3048)
			(stroke
				(width 0.1)
				(type default)
			)
			(layer "F.Fab")
		)
		(fp_line
			(start 0.67945 -0.3048)
			(end 0.67945 0.3048)
			(stroke
				(width 0.1)
				(type default)
			)
			(layer "F.Fab")
		)
		(fp_line
			(start 0.67945 0.3048)
			(end 0.120396 0.3048)
			(stroke
				(width 0.1)
				(type default)
			)
			(layer "F.Fab")
		)
		(pad "1" smd circle
			(at -0.40005 0)
			(size 0 0)
			(layers "F.Cu" "F.Mask" "F.Paste")
			(net "P3V3_AUX")
		)
		(pad "2" smd circle
			(at 0.40005 0)
			(size 0 0)
			(layers "F.Cu" "F.Mask" "F.Paste")
			(net "GND")
		)
	)
)
